# S9S_MB_2U (Grand Teton) — schematic netlist excerpt (pin names and nets, part order shuffled) for the footprints in the layout excerpt that follows; sources: Cadence DE-HDL packaged netlist, KiCad conversion of 03242023_DA0F0TMBIJ0_F0T_Motherboard_J_brd_V01_OCP.brd

PC1852  Q_CAP  0.1UF 25V 10% X7R  pkg 0402  page 258 : A = P5V_AUX ; B = GND
R417  Q_RES  0 5% CHIP  pkg 0402LF  page 153 : A = OCP_SFF_ISO_BIF1_EN ; B = OCP_SFF_BIF1_R_N

(kicad_pcb
	(version 20260206)
	(generator "pcbnew")
	(generator_version "10.0")
	(general
		(thickness 1.6)
		(legacy_teardrops no)
	)
	(paper "A4")
	(title_block
		(title "03242023_DA0F0TMBIJ0_F0T_Motherboard_J_brd_V01_OCP.brd")
		(comment 1 "Grand Teton / footprints 1494-1495 of 6105")
	)
	(layers
		(0 "F.Cu" signal "TOP")
		(4 "In1.Cu" signal "GND")
		(6 "In2.Cu" signal "IN1")
		(8 "In3.Cu" signal "GND1")
		(10 "In4.Cu" signal "IN2")
		(12 "In5.Cu" signal "GND2")
		(14 "In6.Cu" signal "IN3")
		(16 "In7.Cu" signal "GND3")
		(18 "In8.Cu" signal "VCC")
		(20 "In9.Cu" signal "VCC1")
		(22 "In10.Cu" signal "GND4")
		(24 "In11.Cu" signal "IN4")
		(26 "In12.Cu" signal "GND5")
		(28 "In13.Cu" signal "IN5")
		(30 "In14.Cu" signal "GND6")
		(32 "In15.Cu" signal "IN6")
		(34 "In16.Cu" signal "GND7")
		(2 "B.Cu" signal "BOTTOM")
		(9 "F.Adhes" user "F.Adhesive")
		(11 "B.Adhes" user "B.Adhesive")
		(13 "F.Paste" user "Package Geometry/Pastemask Top")
		(15 "B.Paste" user "Package Geometry/Pastemask Bottom")
		(5 "F.SilkS" user "Ref Des/Silkscreen Top")
		(7 "B.SilkS" user "Ref Des/Silkscreen Bottom")
		(1 "F.Mask" user "Board Geometry/Soldermask Top")
		(3 "B.Mask" user "Board Geometry/Soldermask Bottom")
		(17 "Dwgs.User" user "User.Drawings")
		(19 "Cmts.User" user "User.Comments")
		(21 "Eco1.User" user "User.Eco1")
		(23 "Eco2.User" user "User.Eco2")
		(25 "Edge.Cuts" user "Board Geometry/Outline")
		(27 "Margin" user)
		(31 "F.CrtYd" user "Package Geometry/Place Bound Top")
		(29 "B.CrtYd" user "Package Geometry/Place Bound Bottom")
		(35 "F.Fab" user "Ref Des/Assembly Top")
		(33 "B.Fab" user "Ref Des/Assembly Bottom")
	)
	(footprint ""
		(layer "F.Cu")
		(at 437.425846 -380.05258 180)
		(property "Reference" "PC1852"
			(at 0 0 180)
			(layer "F.SilkS")
			(hide yes)
			(effects
				(font
					(size 1.27 1.27)
				)
			)
		)
		(property "Value" ""
			(at 0 0 180)
			(layer "F.Fab")
			(effects
				(font
					(size 1.27 1.27)
				)
			)
		)
		(duplicate_pad_numbers_are_jumpers no)
		(fp_line
			(start 0.7874 0.4064)
			(end -0.7874 0.4064)
			(stroke
				(width 0.1524)
				(type default)
			)
			(layer "F.SilkS")
		)
		(fp_line
			(start 0.7874 -0.4064)
			(end 0.7874 0.4064)
			(stroke
				(width 0.1524)
				(type default)
			)
			(layer "F.SilkS")
		)
		(fp_line
			(start -0.7874 0.4064)
			(end -0.7874 -0.4064)
			(stroke
				(width 0.1524)
				(type default)
			)
			(layer "F.SilkS")
		)
		(fp_line
			(start -0.7874 -0.4064)
			(end 0.7874 -0.4064)
			(stroke
				(width 0.1524)
				(type default)
			)
			(layer "F.SilkS")
		)
		(fp_line
			(start 0.67945 0.3048)
			(end 0.120396 0.3048)
			(stroke
				(width 0.1)
				(type default)
			)
			(layer "F.Fab")
		)
		(fp_line
			(start 0.67945 -0.3048)
			(end 0.67945 0.3048)
			(stroke
				(width 0.1)
				(type default)
			)
			(layer "F.Fab")
		)
		(fp_line
			(start 0.12065 -0.2794)
			(end 0.12065 -0.3048)
			(stroke
				(width 0.1)
				(type default)
			)
			(layer "F.Fab")
		)
		(fp_line
			(start 0.12065 -0.3048)
			(end 0.67945 -0.3048)
			(stroke
				(width 0.1)
				(type default)
			)
			(layer "F.Fab")
		)
		(fp_line
			(start 0.120396 0.3048)
			(end 0.120396 0.2794)
			(stroke
				(width 0.1)
				(type default)
			)
			(layer "F.Fab")
		)
		(fp_line
			(start 0.120396 0.2794)
			(end -0.12065 0.2794)
			(stroke
				(width 0.1)
				(type default)
			)
			(layer "F.Fab")
		)
		(fp_line
			(start -0.12065 0.3048)
			(end -0.67945 0.3048)
			(stroke
				(width 0.1)
				(type default)
			)
			(layer "F.Fab")
		)
		(fp_line
			(start -0.12065 0.2794)
			(end -0.12065 0.3048)
			(stroke
				(width 0.1)
				(type default)
			)
			(layer "F.Fab")
		)
		(fp_line
			(start -0.12065 -0.2794)
			(end 0.12065 -0.2794)
			(stroke
				(width 0.1)
				(type default)
			)
			(layer "F.Fab")
		)
		(fp_line
			(start -0.12065 -0.305054)
			(end -0.12065 -0.2794)
			(stroke
				(width 0.1)
				(type default)
			)
			(layer "F.Fab")
		)
		(fp_line
			(start -0.67945 0.3048)
			(end -0.67945 -0.305054)
			(stroke
				(width 0.1)
				(type default)
			)
			(layer "F.Fab")
		)
		(fp_line
			(start -0.67945 -0.305054)
			(end -0.12065 -0.305054)
			(stroke
				(width 0.1)
				(type default)
			)
			(layer "F.Fab")
		)
		(pad "1" smd circle
			(at -0.40005 0 180)
			(size 0 0)
			(layers "F.Cu" "F.Mask" "F.Paste")
			(net "P5V_AUX")
		)
		(pad "2" smd circle
			(at 0.40005 0 180)
			(size 0 0)
			(layers "F.Cu" "F.Mask" "F.Paste")
			(net "GND")
		)
	)
	(footprint ""
		(layer "F.Cu")
		(at 436.10911 -19.611086 -90)
		(property "Reference" "R417"
			(at 0 0 270)
			(layer "F.SilkS")
			(hide yes)
			(effects
				(font
					(size 1.27 1.27)
				)
			)
		)
		(property "Value" ""
			(at 0 0 270)
			(layer "F.Fab")
			(effects
				(font
					(size 1.27 1.27)
				)
			)
		)
		(duplicate_pad_numbers_are_jumpers no)
		(fp_line
			(start -0.7874 0.4064)
			(end -0.7874 -0.4064)
			(stroke
				(width 0.1524)
				(type default)
			)
			(layer "F.SilkS")
		)
		(fp_line
			(start 0.7874 0.4064)
			(end -0.7874 0.4064)
			(stroke
				(width 0.1524)
				(type default)
			)
			(layer "F.SilkS")
		)
		(fp_line
			(start -0.7874 -0.4064)
			(end 0.7874 -0.4064)
			(stroke
				(width 0.1524)
				(type default)
			)
			(layer "F.SilkS")
		)
		(fp_line
			(start 0.7874 -0.4064)
			(end 0.7874 0.4064)
			(stroke
				(width 0.1524)
				(type default)
			)
			(layer "F.SilkS")
		)
		(fp_line
			(start -0.67945 0.3048)
			(end -0.67945 -0.305054)
			(stroke
				(width 0.1)
				(type default)
			)
			(layer "F.Fab")
		)
		(fp_line
			(start -0.12065 0.3048)
			(end -0.67945 0.3048)
			(stroke
				(width 0.1)
				(type default)
			)
			(layer "F.Fab")
		)
		(fp_line
			(start 0.120396 0.3048)
			(end 0.120396 0.2794)
			(stroke
				(width 0.1)
				(type default)
			)
			(layer "F.Fab")
		)
		(fp_line
			(start 0.67945 0.3048)
			(end 0.120396 0.3048)
			(stroke
				(width 0.1)
				(type default)
			)
			(layer "F.Fab")
		)
		(fp_line
			(start -0.12065 0.2794)
			(end -0.12065 0.3048)
			(stroke
				(width 0.1)
				(type default)
			)
			(layer "F.Fab")
		)
		(fp_line
			(start 0.120396 0.2794)
			(end -0.12065 0.2794)
			(stroke
				(width 0.1)
				(type default)
			)
			(layer "F.Fab")
		)
		(fp_line
			(start -0.12065 -0.2794)
			(end 0.12065 -0.2794)
			(stroke
				(width 0.1)
				(type default)
			)
			(layer "F.Fab")
		)
		(fp_line
			(start 0.12065 -0.2794)
			(end 0.12065 -0.3048)
			(stroke
				(width 0.1)
				(type default)
			)
			(layer "F.Fab")
		)
		(fp_line
			(start 0.12065 -0.3048)
			(end 0.67945 -0.3048)
			(stroke
				(width 0.1)
				(type default)
			)
			(layer "F.Fab")
		)
		(fp_line
			(start 0.67945 -0.3048)
			(end 0.67945 0.3048)
			(stroke
				(width 0.1)
				(type default)
			)
			(layer "F.Fab")
		)
		(fp_line
			(start -0.67945 -0.305054)
			(end -0.12065 -0.305054)
			(stroke
				(width 0.1)
				(type default)
			)
			(layer "F.Fab")
		)
		(fp_line
			(start -0.12065 -0.305054)
			(end -0.12065 -0.2794)
			(stroke
				(width 0.1)
				(type default)
			)
			(layer "F.Fab")
		)
		(pad "1" smd circle
			(at -0.40005 0 270)
			(size 0 0)
			(layers "F.Cu" "F.Mask" "F.Paste")
			(net "OCP_SFF_ISO_BIF1_EN")
		)
		(pad "2" smd circle
			(at 0.40005 0 270)
			(size 0 0)
			(layers "F.Cu" "F.Mask" "F.Paste")
			(net "OCP_SFF_BIF1_R_N")
		)
	)
)
